# TIMECARD (Time Appliance Project (Time Card)) — schematic netlist excerpt (pin names and nets, part order shuffled) for the footprints in the layout excerpt that follows; sources: Cadence DE-HDL packaged netlist, KiCad conversion of R4006-B0001-02_R01.brd

Y1  XTAL_2  pkg SMC_Y2_079X047  page 20 : \1\ = UNNAMED_9_BNO080LGA28_I29_XOUT3 ; \2\ = UNNAMED_9_CAPACITOR_I17_1
C48  CAPACITOR  10UF 25V 20%  pkg SMC_0805R_H057  page 28 : \1\ = VIN_XP3R3 ; \2\ = SG

(kicad_pcb
	(version 20260206)
	(generator "pcbnew")
	(generator_version "10.0")
	(general
		(thickness 1.6)
		(legacy_teardrops no)
	)
	(paper "A4")
	(title_block
		(title "timecard-production-celestica-r4006 — R4006-B0001-02_R01.brd")
		(comment 1 "Time Appliance Project (Time Card) / footprints 354-355 of 1113")
	)
	(layers
		(0 "F.Cu" signal "TOP")
		(4 "In1.Cu" signal "L02_GND1")
		(6 "In2.Cu" signal "L03_SIG1")
		(8 "In3.Cu" signal "L04_GND2")
		(10 "In4.Cu" signal "L05_VCC1")
		(12 "In5.Cu" signal "L06_VCC2")
		(14 "In6.Cu" signal "L07_GND3")
		(16 "In7.Cu" signal "L08_SIG2")
		(18 "In8.Cu" signal "L09_GND4")
		(2 "B.Cu" signal "BOTTOM")
		(9 "F.Adhes" user "F.Adhesive")
		(11 "B.Adhes" user "B.Adhesive")
		(13 "F.Paste" user "Package Geometry/Pastemask Top")
		(15 "B.Paste" user "Package Geometry/Pastemask Bottom")
		(5 "F.SilkS" user "Ref Des/Silkscreen Top")
		(7 "B.SilkS" user "Ref Des/Silkscreen Bottom")
		(1 "F.Mask" user "Board Geometry/Soldermask Top")
		(3 "B.Mask" user "Board Geometry/Soldermask Bottom")
		(17 "Dwgs.User" user "User.Drawings")
		(19 "Cmts.User" user "User.Comments")
		(21 "Eco1.User" user "User.Eco1")
		(23 "Eco2.User" user "User.Eco2")
		(25 "Edge.Cuts" user "Board Geometry/Outline")
		(27 "Margin" user)
		(31 "F.CrtYd" user "Package Geometry/Place Bound Top")
		(29 "B.CrtYd" user "Package Geometry/Place Bound Bottom")
		(35 "F.Fab" user "Ref Des/Assembly Top")
		(33 "B.Fab" user "Ref Des/Assembly Bottom")
	)
	(footprint ""
		(layer "F.Cu")
		(at 90.678 -59.9186 90)
		(property "Reference" "Y1"
			(at 2.4384 0.16637 90)
			(unlocked yes)
			(layer "F.SilkS")
			(effects
				(font
					(size 0.7874 0.5842)
					(thickness 0.1524)
				)
			)
		)
		(property "Value" "VAL*"
			(at -0.038862 5.168646 90)
			(unlocked yes)
			(layer "F.Fab")
			(hide yes)
			(effects
				(font
					(size 0.7874 0.5842)
					(thickness 0.1524)
				)
			)
		)
		(property "User Part Number" "PARTNUM*"
			(at 0 3.255264 90)
			(unlocked yes)
			(layer "Cmts.User")
			(hide yes)
			(effects
				(font
					(size 0.7874 0.5842)
					(thickness 0.1524)
				)
			)
		)
		(property "Device Type" "XTAL_2-G131-10075-01"
			(at 0 2.061464 90)
			(unlocked yes)
			(layer "F.Fab")
			(hide yes)
			(effects
				(font
					(size 0.7874 0.5842)
					(thickness 0.1524)
				)
			)
		)
		(property "Tolerance" "TOL*"
			(at -0.017272 4.188714 90)
			(unlocked yes)
			(layer "Cmts.User")
			(hide yes)
			(effects
				(font
					(size 0.7874 0.5842)
					(thickness 0.1524)
				)
			)
		)
		(duplicate_pad_numbers_are_jumpers no)
		(fp_line
			(start 1.347978 -0.9525)
			(end 1.347978 0.9525)
			(stroke
				(width 0.1)
				(type default)
			)
			(layer "F.SilkS")
		)
		(fp_line
			(start -1.347978 -0.9525)
			(end 1.347978 -0.9525)
			(stroke
				(width 0.1)
				(type default)
			)
			(layer "F.SilkS")
		)
		(fp_line
			(start 1.347978 0.9525)
			(end -1.347978 0.9525)
			(stroke
				(width 0.1)
				(type default)
			)
			(layer "F.SilkS")
		)
		(fp_line
			(start -1.347978 0.9525)
			(end -1.347978 -0.9525)
			(stroke
				(width 0.1)
				(type default)
			)
			(layer "F.SilkS")
		)
		(fp_rect
			(start -1.601978 -1.2065)
			(end 1.601978 1.2065)
			(stroke
				(width 0)
				(type default)
			)
			(fill no)
			(layer "F.CrtYd")
		)
		(fp_line
			(start 1.050036 -0.649986)
			(end 1.050036 0.649986)
			(stroke
				(width 0.1)
				(type default)
			)
			(layer "F.Fab")
		)
		(fp_line
			(start -1.050036 -0.649986)
			(end 1.050036 -0.649986)
			(stroke
				(width 0.1)
				(type default)
			)
			(layer "F.Fab")
		)
		(fp_line
			(start 1.050036 0.649986)
			(end -1.050036 0.649986)
			(stroke
				(width 0.1)
				(type default)
			)
			(layer "F.Fab")
		)
		(fp_line
			(start -1.050036 0.649986)
			(end -1.050036 -0.649986)
			(stroke
				(width 0.1)
				(type default)
			)
			(layer "F.Fab")
		)
		(pad "1" smd rect
			(at -0.674878 0 90)
			(size 0.8382 1.397)
			(layers "F.Cu" "F.Mask" "F.Paste")
			(net "UNNAMED_9_BNO080LGA28_I29_XOUT3")
		)
		(pad "2" smd rect
			(at 0.674878 0 90)
			(size 0.8382 1.397)
			(layers "F.Cu" "F.Mask" "F.Paste")
			(net "UNNAMED_9_CAPACITOR_I17_1")
		)
		(zone
			(layer "F.Cu")
			(hatch none 0.5)
			(connect_pads
				(clearance 0)
			)
			(min_thickness 0.25)
			(keepout
				(tracks allowed)
				(vias not_allowed)
				(pads allowed)
				(copperpour not_allowed)
				(footprints allowed)
			)
			(placement
				(enabled no)
				(sheetname "")
			)
			(fill
				(thermal_gap 0.5)
				(thermal_bridge_width 0.5)
				(island_removal_mode 0)
			)
			(polygon
				(pts
					(xy 90.028014 -59.662822) (xy 91.327986 -59.662822) (xy 91.327986 -60.174378) (xy 90.028014 -60.174378)
				)
			)
		)
	)
	(footprint ""
		(layer "F.Cu")
		(at 84.2772 -97.2058 180)
		(property "Reference" "C48"
			(at 4.3942 -5.67817 0)
			(unlocked yes)
			(layer "F.SilkS")
			(effects
				(font
					(size 0.7874 0.5842)
					(thickness 0.1524)
				)
			)
		)
		(property "Value" "VAL*"
			(at 0.0762 3.134106 180)
			(unlocked yes)
			(layer "F.Fab")
			(hide yes)
			(effects
				(font
					(size 0.7874 0.5842)
					(thickness 0.1524)
				)
			)
		)
		(property "Tolerance" "TOL*"
			(at 0.0762 4.048506 180)
			(unlocked yes)
			(layer "Cmts.User")
			(hide yes)
			(effects
				(font
					(size 0.7874 0.5842)
					(thickness 0.1524)
				)
			)
		)
		(property "User Part Number" "PARTNUM*"
			(at 0.1016 5.013706 180)
			(unlocked yes)
			(layer "Cmts.User")
			(hide yes)
			(effects
				(font
					(size 0.7874 0.5842)
					(thickness 0.1524)
				)
			)
		)
		(property "Device Type" "CAPACITOR-G107-0F106-EM,10UF,2A"
			(at 0.0508 2.194306 180)
			(unlocked yes)
			(layer "F.Fab")
			(hide yes)
			(effects
				(font
					(size 0.7874 0.5842)
					(thickness 0.1524)
				)
			)
		)
		(duplicate_pad_numbers_are_jumpers no)
		(fp_line
			(start 1.5748 0.9398)
			(end 1.5748 -0.9398)
			(stroke
				(width 0.1)
				(type default)
			)
			(layer "F.SilkS")
		)
		(fp_line
			(start 1.5748 -0.9398)
			(end -1.5748 -0.9398)
			(stroke
				(width 0.1)
				(type default)
			)
			(layer "F.SilkS")
		)
		(fp_line
			(start -1.5748 0.9398)
			(end 1.5748 0.9398)
			(stroke
				(width 0.1)
				(type default)
			)
			(layer "F.SilkS")
		)
		(fp_line
			(start -1.5748 -0.9398)
			(end -1.5748 0.9398)
			(stroke
				(width 0.1)
				(type default)
			)
			(layer "F.SilkS")
		)
		(fp_rect
			(start 1.5748 -0.9398)
			(end -1.5748 0.9398)
			(stroke
				(width 0)
				(type default)
			)
			(fill no)
			(layer "F.CrtYd")
		)
		(fp_line
			(start 1.016 0.635)
			(end 1.016 -0.635)
			(stroke
				(width 0.1)
				(type default)
			)
			(layer "F.Fab")
		)
		(fp_line
			(start 1.016 -0.635)
			(end -1.016 -0.635)
			(stroke
				(width 0.1)
				(type default)
			)
			(layer "F.Fab")
		)
		(fp_line
			(start -1.016 0.635)
			(end 1.016 0.635)
			(stroke
				(width 0.1)
				(type default)
			)
			(layer "F.Fab")
		)
		(fp_line
			(start -1.016 -0.635)
			(end -1.016 0.635)
			(stroke
				(width 0.1)
				(type default)
			)
			(layer "F.Fab")
		)
		(pad "1" smd rect
			(at -0.8382 0 180)
			(size 0.9652 1.3716)
			(layers "F.Cu" "F.Mask" "F.Paste")
			(net "VIN_XP3R3")
		)
		(pad "2" smd rect
			(at 0.8382 0 180)
			(size 0.9652 1.3716)
			(layers "F.Cu" "F.Mask" "F.Paste")
			(net "SG")
		)
		(zone
			(layer "F.Cu")
			(hatch none 0.5)
			(connect_pads
				(clearance 0)
			)
			(min_thickness 0.25)
			(keepout
				(tracks allowed)
				(vias not_allowed)
				(pads allowed)
				(copperpour not_allowed)
				(footprints allowed)
			)
			(placement
				(enabled no)
				(sheetname "")
			)
			(fill
				(thermal_gap 0.5)
				(thermal_bridge_width 0.5)
				(island_removal_mode 0)
			)
			(polygon
				(pts
					(xy 84.0486 -96.5708) (xy 84.5058 -96.5708) (xy 84.5058 -97.8408) (xy 84.0486 -97.8408)
				)
			)
		)
	)
)
